# T6G (Grand Teton) — schematic netlist excerpt (pin names and nets, part order shuffled) for the footprints in the layout excerpt that follows; sources: Cadence DE-HDL packaged netlist, KiCad conversion of 04192023_DAF0TMB3IC0_F0TG_MB_C_brd_V02_OCP.brd

R3074  Q_RES  130 1% CHIP  pkg 0402LF  page 254 : A = LED_RST_RSMRST_PLD_R_N ; B = P3V3_AUX
R102  Q_RES  1K 1% EMPTY  pkg 0402LF  page 98 : A = P3V3 ; B = PWRGD_CHAF_CPU1

(kicad_pcb
	(version 20260206)
	(generator "pcbnew")
	(generator_version "10.0")
	(general
		(thickness 1.6)
		(legacy_teardrops no)
	)
	(paper "A4")
	(title_block
		(title "04192023_DAF0TMB3IC0_F0TG_MB_C_brd_V02_OCP.brd")
		(comment 1 "Grand Teton / footprints 6823-6824 of 8354")
	)
	(layers
		(0 "F.Cu" signal "TOP")
		(4 "In1.Cu" signal "GND")
		(6 "In2.Cu" signal "IN1")
		(8 "In3.Cu" signal "GND1")
		(10 "In4.Cu" signal "IN2")
		(12 "In5.Cu" signal "GND2")
		(14 "In6.Cu" signal "IN3")
		(16 "In7.Cu" signal "GND3")
		(18 "In8.Cu" signal "VCC")
		(20 "In9.Cu" signal "VCC1")
		(22 "In10.Cu" signal "GND4")
		(24 "In11.Cu" signal "IN4")
		(26 "In12.Cu" signal "GND5")
		(28 "In13.Cu" signal "IN5")
		(30 "In14.Cu" signal "GND6")
		(32 "In15.Cu" signal "IN6")
		(34 "In16.Cu" signal "GND7")
		(2 "B.Cu" signal "BOTTOM")
		(9 "F.Adhes" user "F.Adhesive")
		(11 "B.Adhes" user "B.Adhesive")
		(13 "F.Paste" user "Package Geometry/Pastemask Top")
		(15 "B.Paste" user "Package Geometry/Pastemask Bottom")
		(5 "F.SilkS" user "Ref Des/Silkscreen Top")
		(7 "B.SilkS" user "Ref Des/Silkscreen Bottom")
		(1 "F.Mask" user "Board Geometry/Soldermask Top")
		(3 "B.Mask" user "Board Geometry/Soldermask Bottom")
		(17 "Dwgs.User" user "User.Drawings")
		(19 "Cmts.User" user "User.Comments")
		(21 "Eco1.User" user "User.Eco1")
		(23 "Eco2.User" user "User.Eco2")
		(25 "Edge.Cuts" user "Board Geometry/Outline")
		(27 "Margin" user)
		(31 "F.CrtYd" user "Package Geometry/Place Bound Top")
		(29 "B.CrtYd" user "Package Geometry/Place Bound Bottom")
		(35 "F.Fab" user "Ref Des/Assembly Top")
		(33 "B.Fab" user "Ref Des/Assembly Bottom")
	)
	(footprint ""
		(layer "B.Cu")
		(at 50.586386 -190.821564 180)
		(property "Reference" "R102"
			(at 0 0 0)
			(layer "B.SilkS")
			(hide yes)
			(effects
				(font
					(size 1.27 1.27)
				)
				(justify mirror)
			)
		)
		(property "Value" ""
			(at 0 0 0)
			(layer "B.Fab")
			(effects
				(font
					(size 1.27 1.27)
				)
				(justify mirror)
			)
		)
		(duplicate_pad_numbers_are_jumpers no)
		(fp_line
			(start 0.7874 0.4064)
			(end 0.7874 -0.4064)
			(stroke
				(width 0.1524)
				(type default)
			)
			(layer "B.SilkS")
		)
		(fp_line
			(start 0.7874 -0.4064)
			(end -0.7874 -0.4064)
			(stroke
				(width 0.1524)
				(type default)
			)
			(layer "B.SilkS")
		)
		(fp_line
			(start -0.7874 0.4064)
			(end 0.7874 0.4064)
			(stroke
				(width 0.1524)
				(type default)
			)
			(layer "B.SilkS")
		)
		(fp_line
			(start -0.7874 -0.4064)
			(end -0.7874 0.4064)
			(stroke
				(width 0.1524)
				(type default)
			)
			(layer "B.SilkS")
		)
		(fp_line
			(start 0.67945 0.3048)
			(end 0.67945 -0.305054)
			(stroke
				(width 0.1)
				(type default)
			)
			(layer "B.Fab")
		)
		(fp_line
			(start 0.67945 -0.305054)
			(end 0.12065 -0.305054)
			(stroke
				(width 0.1)
				(type default)
			)
			(layer "B.Fab")
		)
		(fp_line
			(start 0.12065 0.3048)
			(end 0.67945 0.3048)
			(stroke
				(width 0.1)
				(type default)
			)
			(layer "B.Fab")
		)
		(fp_line
			(start 0.12065 0.2794)
			(end 0.12065 0.3048)
			(stroke
				(width 0.1)
				(type default)
			)
			(layer "B.Fab")
		)
		(fp_line
			(start 0.12065 -0.2794)
			(end -0.12065 -0.2794)
			(stroke
				(width 0.1)
				(type default)
			)
			(layer "B.Fab")
		)
		(fp_line
			(start 0.12065 -0.305054)
			(end 0.12065 -0.2794)
			(stroke
				(width 0.1)
				(type default)
			)
			(layer "B.Fab")
		)
		(fp_line
			(start -0.120396 0.3048)
			(end -0.120396 0.2794)
			(stroke
				(width 0.1)
				(type default)
			)
			(layer "B.Fab")
		)
		(fp_line
			(start -0.120396 0.2794)
			(end 0.12065 0.2794)
			(stroke
				(width 0.1)
				(type default)
			)
			(layer "B.Fab")
		)
		(fp_line
			(start -0.12065 -0.2794)
			(end -0.12065 -0.3048)
			(stroke
				(width 0.1)
				(type default)
			)
			(layer "B.Fab")
		)
		(fp_line
			(start -0.12065 -0.3048)
			(end -0.67945 -0.3048)
			(stroke
				(width 0.1)
				(type default)
			)
			(layer "B.Fab")
		)
		(fp_line
			(start -0.67945 0.3048)
			(end -0.120396 0.3048)
			(stroke
				(width 0.1)
				(type default)
			)
			(layer "B.Fab")
		)
		(fp_line
			(start -0.67945 -0.3048)
			(end -0.67945 0.3048)
			(stroke
				(width 0.1)
				(type default)
			)
			(layer "B.Fab")
		)
		(pad "1" smd circle
			(at 0.40005 0)
			(size 0 0)
			(layers "B.Cu" "B.Mask" "B.Paste")
			(net "P3V3")
		)
		(pad "2" smd circle
			(at -0.40005 0)
			(size 0 0)
			(layers "B.Cu" "B.Mask" "B.Paste")
			(net "PWRGD_CHAF_CPU1")
		)
	)
	(footprint ""
		(layer "B.Cu")
		(at 310.411876 -66.708782 90)
		(property "Reference" "R3074"
			(at 0 0 90)
			(layer "B.SilkS")
			(hide yes)
			(effects
				(font
					(size 1.27 1.27)
				)
				(justify mirror)
			)
		)
		(property "Value" ""
			(at 0 0 90)
			(layer "B.Fab")
			(effects
				(font
					(size 1.27 1.27)
				)
				(justify mirror)
			)
		)
		(duplicate_pad_numbers_are_jumpers no)
		(fp_line
			(start 0.7874 -0.4064)
			(end -0.7874 -0.4064)
			(stroke
				(width 0.1524)
				(type default)
			)
			(layer "B.SilkS")
		)
		(fp_line
			(start -0.7874 -0.4064)
			(end -0.7874 0.4064)
			(stroke
				(width 0.1524)
				(type default)
			)
			(layer "B.SilkS")
		)
		(fp_line
			(start 0.7874 0.4064)
			(end 0.7874 -0.4064)
			(stroke
				(width 0.1524)
				(type default)
			)
			(layer "B.SilkS")
		)
		(fp_line
			(start -0.7874 0.4064)
			(end 0.7874 0.4064)
			(stroke
				(width 0.1524)
				(type default)
			)
			(layer "B.SilkS")
		)
		(fp_line
			(start 0.67945 -0.305054)
			(end 0.12065 -0.305054)
			(stroke
				(width 0.1)
				(type default)
			)
			(layer "B.Fab")
		)
		(fp_line
			(start 0.12065 -0.305054)
			(end 0.12065 -0.2794)
			(stroke
				(width 0.1)
				(type default)
			)
			(layer "B.Fab")
		)
		(fp_line
			(start -0.12065 -0.3048)
			(end -0.67945 -0.3048)
			(stroke
				(width 0.1)
				(type default)
			)
			(layer "B.Fab")
		)
		(fp_line
			(start -0.67945 -0.3048)
			(end -0.67945 0.3048)
			(stroke
				(width 0.1)
				(type default)
			)
			(layer "B.Fab")
		)
		(fp_line
			(start 0.12065 -0.2794)
			(end -0.12065 -0.2794)
			(stroke
				(width 0.1)
				(type default)
			)
			(layer "B.Fab")
		)
		(fp_line
			(start -0.12065 -0.2794)
			(end -0.12065 -0.3048)
			(stroke
				(width 0.1)
				(type default)
			)
			(layer "B.Fab")
		)
		(fp_line
			(start 0.12065 0.2794)
			(end 0.12065 0.3048)
			(stroke
				(width 0.1)
				(type default)
			)
			(layer "B.Fab")
		)
		(fp_line
			(start -0.120396 0.2794)
			(end 0.12065 0.2794)
			(stroke
				(width 0.1)
				(type default)
			)
			(layer "B.Fab")
		)
		(fp_line
			(start 0.67945 0.3048)
			(end 0.67945 -0.305054)
			(stroke
				(width 0.1)
				(type default)
			)
			(layer "B.Fab")
		)
		(fp_line
			(start 0.12065 0.3048)
			(end 0.67945 0.3048)
			(stroke
				(width 0.1)
				(type default)
			)
			(layer "B.Fab")
		)
		(fp_line
			(start -0.120396 0.3048)
			(end -0.120396 0.2794)
			(stroke
				(width 0.1)
				(type default)
			)
			(layer "B.Fab")
		)
		(fp_line
			(start -0.67945 0.3048)
			(end -0.120396 0.3048)
			(stroke
				(width 0.1)
				(type default)
			)
			(layer "B.Fab")
		)
		(pad "1" smd circle
			(at 0.40005 0 270)
			(size 0 0)
			(layers "B.Cu" "B.Mask" "B.Paste")
			(net "LED_RST_RSMRST_PLD_R_N")
		)
		(pad "2" smd circle
			(at -0.40005 0 270)
			(size 0 0)
			(layers "B.Cu" "B.Mask" "B.Paste")
			(net "P3V3_AUX")
		)
	)
)
